#ISCELL
  mstr_misc dns *
  *
#ISCELL
  pure_quanta quanta_title_block_c *
  *
#ISCELL
  pure_quanta_power design_note *
  *
#ISCELL
  standard offpage *
  page257_i1
#CELL
  pure_quanta q_res *
  page257_i10
#ISCELL
  pure_quanta_power universal_power *
  page257_i11
#CELL
  pure_quanta q_res *
  page257_i12
#ISCELL
  pure_quanta_power universal_gnd *
  page257_i13
#CELL
  pure_quanta q_cap *
  page257_i14
#ISCELL
  pure_quanta_power universal_power *
  page257_i15
#CELL
  pure_quanta q_res *
  page257_i16
#CELL
  pure_quanta q_res *
  page257_i17
#CELL
  pure_quanta q_res *
  page257_i18
#CELL
  pure_quanta q_res *
  page257_i19
#ISCELL
  standard offpage *
  page257_i2
#ISCELL
  pure_quanta_power universal_power *
  page257_i20
#ISCELL
  standard offpage *
  page257_i21
#ISCELL
  standard offpage *
  page257_i22
#ISCELL
  pure_quanta_power universal_gnd *
  page257_i23
#CELL
  pure_quanta mosfet_n *
  page257_i24
#CELL
  pure_quanta q_res *
  page257_i25
#ISCELL
  pure_quanta_power universal_power *
  page257_i26
#ISCELL
  standard offpage *
  page257_i27
#CELL
  pure_quanta q_res *
  page257_i28
#ISCELL
  standard offpage *
  page257_i29
#CELL
  pure_quanta q_res *
  page257_i3
#ISCELL
  pure_quanta_power universal_gnd *
  page257_i30
#CELL
  pure_quanta 74lvc1g08w57 *
  page257_i31
#CELL
  pure_quanta q_res *
  page257_i32
#ISCELL
  pure_quanta_power universal_power *
  page257_i33
#CELL
  pure_quanta q_res *
  page257_i34
#ISCELL
  pure_quanta_power universal_gnd *
  page257_i35
#CELL
  pure_quanta q_cap *
  page257_i36
#ISCELL
  pure_quanta_power universal_power *
  page257_i37
#ISCELL
  pure_quanta_power universal_gnd *
  page257_i38
#CELL
  pure_quanta q_res *
  page257_i39
#ISCELL
  pure_quanta_power universal_gnd *
  page257_i4
#CELL
  pure_quanta 74lvc1g32gw *
  page257_i40
#CELL
  pure_quanta q_res *
  page257_i41
#CELL
  pure_quanta q_res *
  page257_i42
#ISCELL
  pure_quanta_power universal_gnd *
  page257_i43
#ISCELL
  pure_quanta_power universal_gnd *
  page257_i44
#CELL
  pure_quanta sn74lvc1g07dbvr *
  page257_i45
#CELL
  pure_quanta q_cap *
  page257_i46
#ISCELL
  pure_quanta_power universal_gnd *
  page257_i47
#ISCELL
  pure_quanta_power universal_power *
  page257_i48
#CELL
  pure_quanta q_res *
  page257_i49
#CELL
  pure_quanta q_cap *
  page257_i5
#ISCELL
  standard offpage *
  page257_i50
#CELL
  pure_quanta q_res *
  page257_i51
#ISCELL
  pure_quanta_power universal_power *
  page257_i52
#ISCELL
  standard offpage *
  page257_i53
#ISCELL
  pure_quanta_power universal_gnd *
  page257_i54
#CELL
  pure_quanta q_cap *
  page257_i55
#ISCELL
  pure_quanta_power universal_power *
  page257_i56
#CELL
  pure_quanta q_res *
  page257_i57
#CELL
  pure_quanta q_res *
  page257_i58
#ISCELL
  standard offpage *
  page257_i59
#ISCELL
  pure_quanta_power universal_power *
  page257_i6
#CELL
  pure_quanta q_res *
  page257_i60
#ISCELL
  pure_quanta_power universal_power *
  page257_i61
#ISCELL
  standard offpage *
  page257_i62
#CELL
  pure_quanta 74lvc1g08w57 *
  page257_i63
#CELL
  pure_quanta sn74lvc1g07dbvr *
  page257_i64
#ISCELL
  pure_quanta_power universal_gnd *
  page257_i65
#CELL
  pure_quanta q_cap *
  page257_i66
#CELL
  pure_quanta apx80929sag7 *
  page257_i67
#ISCELL
  pure_quanta_power universal_power *
  page257_i68
#ISCELL
  pure_quanta_power universal_gnd *
  page257_i69
#ISCELL
  standard offpage *
  page257_i7
#CELL
  pure_quanta q_res *
  page257_i70
#ISCELL
  pure_quanta_power universal_gnd *
  page257_i71
#ISCELL
  pure_quanta_power universal_power *
  page257_i72
#CELL
  pure_quanta q_res *
  page257_i73
#ISCELL
  standard offpage *
  page257_i74
#CELL
  pure_quanta q_res *
  page257_i77
#CELL
  pure_quanta 74lvc1g08w57 *
  page257_i78
#ISCELL
  pure_quanta_power universal_gnd *
  page257_i79
#ISCELL
  standard offpage *
  page257_i8
#ISCELL
  pure_quanta_power universal_power *
  page257_i80
#CELL
  pure_quanta q_cap *
  page257_i81
#ISCELL
  pure_quanta_power universal_gnd *
  page257_i82
#ISCELL
  standard offpage *
  page257_i83
#CELL
  pure_quanta q_res *
  page257_i84
#ISCELL
  standard offpage *
  page257_i85
#ISCELL
  standard offpage *
  page257_i86
#ISCELL
  standard offpage *
  page257_i87
#CELL
  pure_quanta q_res *
  page257_i88
#CELL
  pure_quanta q_res *
  page257_i89
#ISCELL
  pure_quanta_power universal_gnd *
  page257_i9
